FILE_TYPE = MACRO_DRAWING;
SET COLOR_WIRE YELLOW;
SET COLOR_PROP ORANGE;
SET COLOR_DOT WHITE;
SET COLOR_ARC YELLOW;
SET COLOR_BODY GREEN;
SET COLOR_NOTE PURPLE;
SET PROP_DISPLAY VALUE;
SET PAGE_NUMBER P56;
FORCEADD OFFPAGE..1
(-7625 4250);
FORCEPROP 2 LAST $XR0 76 
J 0
(-7846 4250);
DISPLAY 0.638298 (-7846 4250);
PAINT MONO (-7846 4250);
FORCEPROP 2 LAST CDS_LIB standard
J 0
(-7625 4250);
DISPLAY INVISIBLE (-7625 4250);
FORCEPROP 1 LAST OFFPAGE TRUE
J 0
(-7300 4125);
DISPLAY 0.872340 (-7300 4125);
PAINT GREEN (-7300 4125);
DISPLAY INVISIBLE (-7300 4125);
FORCEPROP 1 LAST COMMENT_BODY TRUE
J 0
(-7500 4150);
DISPLAY 0.872340 (-7500 4150);
PAINT GREEN (-7500 4150);
DISPLAY INVISIBLE (-7500 4150);
FORCEPROP 2 LAST PATH I10
J 0
(-7875 4300);
DISPLAY 1.021277 (-7875 4300);
DISPLAY INVISIBLE (-7875 4300);
FORCEADD Q_RES..1
(-6800 5500);
FORCEPROP 1 LAST LOCATION R738
J 0
(-6675 5500);
DISPLAY 0.489362 (-6675 5500);
PAINT SKYBLUE (-6675 5500);
FORCEPROP 0 LAST $SEC 1
J 0
(-6675 5525);
DISPLAY 0.680851 (-6675 5525);
PAINT MONO (-6675 5525);
DISPLAY INVISIBLE (-6675 5525);
FORCEPROP 0 LAST CDS_SEC 1
J 0
(-6675 5525);
DISPLAY 0.680851 (-6675 5525);
DISPLAY INVISIBLE (-6675 5525);
FORCEPROP 1 LASTPIN (-6900 5500) $PN 1
J 0
(-6888 5512);
DISPLAY 0.489362 (-6888 5512);
PAINT MONO (-6888 5512);
FORCEPROP 1 LASTPIN (-6700 5500) $PN 2
J 0
(-6738 5512);
DISPLAY 0.489362 (-6738 5512);
PAINT MONO (-6738 5512);
FORCEPROP 1 LAST VALUE 33
J 2
(-6900 5500);
DISPLAY 0.489362 (-6900 5500);
PAINT SKYBLUE (-6900 5500);
FORCEPROP 1 LAST PACK_TYPE 0402LF
J 0
(-6750 5425);
DISPLAY 0.489362 (-6750 5425);
PAINT SKYBLUE (-6750 5425);
DISPLAY INVISIBLE (-6750 5425);
FORCEPROP 1 LAST TOLERANCE 5%
J 0
(-6825 5425);
DISPLAY 0.489362 (-6825 5425);
PAINT SKYBLUE (-6825 5425);
DISPLAY INVISIBLE (-6825 5425);
FORCEPROP 1 LAST MATERIAL CHIP
J 0
(-6375 5425);
DISPLAY 0.489362 (-6375 5425);
PAINT SKYBLUE (-6375 5425);
DISPLAY INVISIBLE (-6375 5425);
FORCEPROP 1 LAST WATTAGE 1/16W
J 2
(-6400 5425);
DISPLAY 0.489362 (-6400 5425);
PAINT SKYBLUE (-6400 5425);
DISPLAY INVISIBLE (-6400 5425);
FORCEPROP 2 LAST CDS_LIB pure_quanta
J 0
(-6800 5500);
DISPLAY INVISIBLE (-6800 5500);
FORCEPROP 1 LAST PATH I11
J 0
(-6850 5650);
DISPLAY 0.978723 (-6850 5650);
PAINT WHITE (-6850 5650);
DISPLAY INVISIBLE (-6850 5650);
FORCEPROP 1 LAST PART_NUMBER CS03302JB10
J 0
(-6775 5550);
DISPLAY 0.489362 (-6775 5550);
PAINT SKYBLUE (-6775 5550);
DISPLAY INVISIBLE (-6775 5550);
FORCEADD OFFPAGE..2
R 2
(-7625 5500);
FORCEPROP 2 LAST $XR0 76 
J 0
(-7879 5500);
DISPLAY 0.638298 (-7879 5500);
PAINT MONO (-7879 5500);
FORCEPROP 2 LAST CDS_LIB standard
J 2
(-7625 5500);
DISPLAY INVISIBLE (-7625 5500);
FORCEPROP 1 LAST OFFPAGE TRUE
J 2
(-7950 5375);
DISPLAY 0.872340 (-7950 5375);
PAINT GREEN (-7950 5375);
DISPLAY INVISIBLE (-7950 5375);
FORCEPROP 1 LAST COMMENT_BODY TRUE
J 2
(-7580 5405);
DISPLAY 0.872340 (-7580 5405);
PAINT PEACH (-7580 5405);
DISPLAY INVISIBLE (-7580 5405);
FORCEPROP 2 LAST PATH I12
J 0
(-7875 5550);
DISPLAY 0.680851 (-7875 5550);
DISPLAY INVISIBLE (-7875 5550);
FORCEADD GENOA_SP5..22
(-4525 4675);
FORCEPROP 1 LAST LOCATION U26
J 0
(-5620 6206);
DISPLAY 0.489362 (-5620 6206);
PAINT SKYBLUE (-5620 6206);
FORCEPROP 0 LAST $SEC 22
J 0
(-5600 6250);
DISPLAY 0.680851 (-5600 6250);
PAINT MONO (-5600 6250);
DISPLAY INVISIBLE (-5600 6250);
FORCEPROP 0 LAST CDS_SEC 22
J 0
(-5625 6225);
DISPLAY 1.021277 (-5625 6225);
DISPLAY INVISIBLE (-5625 6225);
FORCEPROP 0 LASTPIN (-5775 4100) $PN DJ25
J 2
(-5785 4110);
DISPLAY 0.489362 (-5785 4110);
PAINT MONO (-5785 4110);
FORCEPROP 0 LASTPIN (-5775 4350) $PN DJ22
J 2
(-5785 4360);
DISPLAY 0.489362 (-5785 4360);
PAINT MONO (-5785 4360);
FORCEPROP 0 LASTPIN (-5775 5100) $PN DF28
J 2
(-5785 5110);
DISPLAY 0.489362 (-5785 5110);
PAINT MONO (-5785 5110);
FORCEPROP 0 LASTPIN (-5775 5050) $PN DG22
J 2
(-5785 5060);
DISPLAY 0.489362 (-5785 5060);
PAINT MONO (-5785 5060);
FORCEPROP 0 LASTPIN (-5775 5000) $PN DJ28
J 2
(-5785 5010);
DISPLAY 0.489362 (-5785 5010);
PAINT MONO (-5785 5010);
FORCEPROP 0 LASTPIN (-5775 4950) $PN DG29
J 2
(-5785 4960);
DISPLAY 0.489362 (-5785 4960);
PAINT MONO (-5785 4960);
FORCEPROP 0 LASTPIN (-5775 4500) $PN DF24
J 2
(-5785 4510);
DISPLAY 0.489362 (-5785 4510);
PAINT MONO (-5785 4510);
FORCEPROP 0 LASTPIN (-5775 4800) $PN DH24
J 2
(-5785 4810);
DISPLAY 0.489362 (-5785 4810);
PAINT MONO (-5785 4810);
FORCEPROP 0 LASTPIN (-5775 4750) $PN DE24
J 2
(-5785 4760);
DISPLAY 0.489362 (-5785 4760);
PAINT MONO (-5785 4760);
FORCEPROP 0 LASTPIN (-5775 4700) $PN DF25
J 2
(-5785 4710);
DISPLAY 0.489362 (-5785 4710);
PAINT MONO (-5785 4710);
FORCEPROP 0 LASTPIN (-5775 4650) $PN DG25
J 2
(-5785 4660);
DISPLAY 0.489362 (-5785 4660);
PAINT MONO (-5785 4660);
FORCEPROP 0 LASTPIN (-5775 5500) $PN DJ27
J 2
(-5785 5510);
DISPLAY 0.489362 (-5785 5510);
PAINT MONO (-5785 5510);
FORCEPROP 0 LASTPIN (-5775 4300) $PN DG23
J 2
(-5785 4310);
DISPLAY 0.489362 (-5785 4310);
PAINT MONO (-5785 4310);
FORCEPROP 0 LASTPIN (-5775 4250) $PN DF27
J 2
(-5785 4260);
DISPLAY 0.489362 (-5785 4260);
PAINT MONO (-5785 4260);
FORCEPROP 0 LASTPIN (-5775 5450) $PN DG28
J 2
(-5785 5460);
DISPLAY 0.489362 (-5785 5460);
PAINT MONO (-5785 5460);
FORCEPROP 0 LASTPIN (-5775 5400) $PN DJ23
J 2
(-5785 5410);
DISPLAY 0.489362 (-5785 5410);
PAINT MONO (-5785 5410);
FORCEPROP 0 LASTPIN (-5775 5300) $PN DJ26
J 2
(-5785 5310);
DISPLAY 0.489362 (-5785 5310);
PAINT MONO (-5785 5310);
FORCEPROP 0 LASTPIN (-5775 4200) $PN DE27
J 2
(-5785 4210);
DISPLAY 0.489362 (-5785 4210);
PAINT MONO (-5785 4210);
FORCEPROP 0 LASTPIN (-5775 5750) $PN DF30
J 2
(-5785 5760);
DISPLAY 0.489362 (-5785 5760);
PAINT MONO (-5785 5760);
FORCEPROP 0 LASTPIN (-5775 5700) $PN DG26
J 2
(-5785 5710);
DISPLAY 0.489362 (-5785 5710);
PAINT MONO (-5785 5710);
FORCEPROP 0 LASTPIN (-5775 5650) $PN DH27
J 2
(-5785 5660);
DISPLAY 0.489362 (-5785 5660);
PAINT MONO (-5785 5660);
FORCEPROP 0 LASTPIN (-3275 5700) $PN A25
J 0
(-3265 5710);
DISPLAY 0.489362 (-3265 5710);
PAINT MONO (-3265 5710);
FORCEPROP 0 LASTPIN (-3275 5750) $PN A26
J 0
(-3265 5760);
DISPLAY 0.489362 (-3265 5760);
PAINT MONO (-3265 5760);
FORCEPROP 0 LASTPIN (-3275 3800) $PN E23
J 0
(-3265 3810);
DISPLAY 0.489362 (-3265 3810);
PAINT MONO (-3265 3810);
FORCEPROP 0 LASTPIN (-3275 5050) $PN E26
J 0
(-3265 5060);
DISPLAY 0.489362 (-3265 5060);
PAINT MONO (-3265 5060);
FORCEPROP 0 LASTPIN (-3275 5100) $PN E27
J 0
(-3265 5110);
DISPLAY 0.489362 (-3265 5110);
PAINT MONO (-3265 5110);
FORCEPROP 0 LASTPIN (-3275 4400) $PN C26
J 0
(-3265 4410);
DISPLAY 0.489362 (-3265 4410);
PAINT MONO (-3265 4410);
FORCEPROP 0 LASTPIN (-3275 4450) $PN C25
J 0
(-3265 4460);
DISPLAY 0.489362 (-3265 4460);
PAINT MONO (-3265 4460);
FORCEPROP 0 LASTPIN (-3275 5550) $PN A29
J 0
(-3265 5560);
DISPLAY 0.489362 (-3265 5560);
PAINT MONO (-3265 5560);
FORCEPROP 0 LASTPIN (-3275 5600) $PN A28
J 0
(-3265 5610);
DISPLAY 0.489362 (-3265 5610);
PAINT MONO (-3265 5610);
FORCEPROP 0 LASTPIN (-3275 3750) $PN E24
J 0
(-3265 3760);
DISPLAY 0.489362 (-3265 3760);
PAINT MONO (-3265 3760);
FORCEPROP 0 LASTPIN (-3275 4900) $PN C28
J 0
(-3265 4910);
DISPLAY 0.489362 (-3265 4910);
PAINT MONO (-3265 4910);
FORCEPROP 0 LASTPIN (-3275 4950) $PN C29
J 0
(-3265 4960);
DISPLAY 0.489362 (-3265 4960);
PAINT MONO (-3265 4960);
FORCEPROP 0 LASTPIN (-3275 4250) $PN E29
J 0
(-3265 4260);
DISPLAY 0.489362 (-3265 4260);
PAINT MONO (-3265 4260);
FORCEPROP 0 LASTPIN (-3275 4300) $PN E30
J 0
(-3265 4310);
DISPLAY 0.489362 (-3265 4310);
PAINT MONO (-3265 4310);
FORCEPROP 0 LASTPIN (-3275 5400) $PN DH67
J 0
(-3265 5410);
DISPLAY 0.489362 (-3265 5410);
PAINT MONO (-3265 5410);
FORCEPROP 0 LASTPIN (-3275 5450) $PN DJ67
J 0
(-3265 5460);
DISPLAY 0.489362 (-3265 5460);
PAINT MONO (-3265 5460);
FORCEPROP 0 LASTPIN (-3275 3700) $PN DG40
J 0
(-3265 3710);
DISPLAY 0.489362 (-3265 3710);
PAINT MONO (-3265 3710);
FORCEPROP 0 LASTPIN (-3275 4750) $PN DH65
J 0
(-3265 4760);
DISPLAY 0.489362 (-3265 4760);
PAINT MONO (-3265 4760);
FORCEPROP 0 LASTPIN (-3275 4800) $PN DJ65
J 0
(-3265 4810);
DISPLAY 0.489362 (-3265 4810);
PAINT MONO (-3265 4810);
FORCEPROP 0 LASTPIN (-3275 4100) $PN DJ69
J 0
(-3265 4110);
DISPLAY 0.489362 (-3265 4110);
PAINT MONO (-3265 4110);
FORCEPROP 0 LASTPIN (-3275 4150) $PN DH69
J 0
(-3265 4160);
DISPLAY 0.489362 (-3265 4160);
PAINT MONO (-3265 4160);
FORCEPROP 0 LASTPIN (-3275 5250) $PN DJ60
J 0
(-3265 5260);
DISPLAY 0.489362 (-3265 5260);
PAINT MONO (-3265 5260);
FORCEPROP 0 LASTPIN (-3275 5300) $PN DH60
J 0
(-3265 5310);
DISPLAY 0.489362 (-3265 5310);
PAINT MONO (-3265 5310);
FORCEPROP 0 LASTPIN (-3275 3650) $PN DH40
J 0
(-3265 3660);
DISPLAY 0.489362 (-3265 3660);
PAINT MONO (-3265 3660);
FORCEPROP 0 LASTPIN (-3275 4600) $PN DH62
J 0
(-3265 4610);
DISPLAY 0.489362 (-3265 4610);
PAINT MONO (-3265 4610);
FORCEPROP 0 LASTPIN (-3275 4650) $PN DJ62
J 0
(-3265 4660);
DISPLAY 0.489362 (-3265 4660);
PAINT MONO (-3265 4660);
FORCEPROP 0 LASTPIN (-3275 3950) $PN DH58
J 0
(-3265 3960);
DISPLAY 0.489362 (-3265 3960);
PAINT MONO (-3265 3960);
FORCEPROP 0 LASTPIN (-3275 4000) $PN DG58
J 0
(-3265 4010);
DISPLAY 0.489362 (-3265 4010);
PAINT MONO (-3265 4010);
FORCEPROP 2 LAST PART_TYPE SMLF
J 0
(-5625 6175);
DISPLAY 1.021277 (-5625 6175);
FORCEPROP 1 LAST MATERIAL IO
J 0
(-5620 5932);
DISPLAY 0.489362 (-5620 5932);
PAINT SKYBLUE (-5620 5932);
FORCEPROP 2 LAST VALUE SOCKET6096_13568-001
J 0
(-5625 6075);
DISPLAY 0.489362 (-5625 6075);
PAINT SKYBLUE (-5625 6075);
FORCEPROP 1 LAST NEEDS_NO_SIZE TRUE
J 0
(-4525 4675);
DISPLAY 0.723404 (-4525 4675);
PAINT GREEN (-4525 4675);
DISPLAY INVISIBLE (-4525 4675);
FORCEPROP 1 LAST CDS_LMAN_SYM_OUTLINE -1100,1225,1100,-1225
J 0
(-4525 4675);
DISPLAY 0.468085 (-4525 4675);
PAINT GREEN (-4525 4675);
DISPLAY INVISIBLE (-4525 4675);
FORCEPROP 2 LAST CDS_LIB pure_quanta
J 0
(-4525 4675);
DISPLAY INVISIBLE (-4525 4675);
FORCEPROP 1 LAST PATH I8
J 0
(-4525 4675);
DISPLAY 0.723404 (-4525 4675);
PAINT GREEN (-4525 4675);
DISPLAY INVISIBLE (-4525 4675);
FORCEPROP 1 LAST PART_NUMBER DGA^6000030
J 0
(-5620 6059);
DISPLAY 0.489362 (-5620 6059);
PAINT SKYBLUE (-5620 6059);
DISPLAY INVISIBLE (-5620 6059);
FORCEADD QUANTA_TITLE_BLOCK_C..1
(0 0);
FORCEPROP 0 LAST CDS_CON_LAST_MODIFIED Thu Sep 14 16:12:00 2023
J 0
(-1885 15);
DISPLAY INVISIBLE (-1885 15);
FORCEPROP 1 LAST CUSTOM_TXT_CDS <CON_LAST_MODIFIED>
J 0
(-1885 15);
DISPLAY 0.978723 (-1885 15);
FORCEPROP 2 LAST CUSTOM_TXT_CDS <XR_PAGE_TITLE>
J 0
(-7890 5250);
DISPLAY 0.638298 (-7890 5250);
PAINT PINK (-7890 5250);
DISPLAY INVISIBLE (-7890 5250);
FORCEPROP 1 LAST CUSTOM_TXT_CDS <NAME_2>
J 0
(-3175 50);
FORCEPROP 1 LAST CUSTOM_TXT_CDS <NAME_1>
J 0
(-3175 175);
FORCEPROP 1 LAST CUSTOM_TXT_CDS <Q_NUMBER>
J 0
(-1403 103);
DISPLAY 1.212766 (-1403 103);
FORCEPROP 1 LAST CUSTOM_TXT_CDS <Q_PROJ>
J 0
(-2382 102);
DISPLAY 1.212766 (-2382 102);
FORCEPROP 1 LAST CUSTOM_TXT_CDS <Q_REV>
J 0
(-184 103);
DISPLAY 1.212766 (-184 103);
FORCEPROP 1 LAST CUSTOM_TXT_CDS <CON_PAGE_NUM> OF <CON_TOTAL_PAGES>
J 0
(-446 18);
DISPLAY 0.978723 (-446 18);
FORCEPROP 1 LAST Q_TITLE CPU1 SPI/USB
J 0
(-9300 50);
DISPLAY 2.446809 (-9300 50);
PAINT GREEN (-9300 50);
FORCEPROP 2 LAST CDS_LIB pure_quanta
J 0
(0 0);
DISPLAY INVISIBLE (0 0);
FORCEPROP 1 LAST CDS_LMAN_SYM_OUTLINE -9475,6775,100,-125
J 0
(0 0);
DISPLAY 0.468085 (0 0);
PAINT GREEN (0 0);
DISPLAY INVISIBLE (0 0);
FORCEPROP 2 LAST PAGE_BORDER TRUE
J 0
(-7890 5250);
DISPLAY 0.638298 (-7890 5250);
PAINT PINK (-7890 5250);
DISPLAY INVISIBLE (-7890 5250);
FORCEPROP 2 LAST CDS_XR_PAGE_TITLE CR-56 : @T6G_MB_LIB.T6G(SCH_1):PAGE56
J 0
(-7890 5250);
DISPLAY 0.638298 (-7890 5250);
PAINT PINK (-7890 5250);
DISPLAY INVISIBLE (-7890 5250);
FORCEPROP 1 LAST Q_DEPT BU9
J 1
(-3763 49);
DISPLAY 1.957447 (-3763 49);
PAINT GREEN (-3763 49);
DISPLAY INVISIBLE (-3763 49);
FORCEPROP 1 LAST COMMENT_BODY TRUE
J 0
(12 -13);
DISPLAY 0.978723 (12 -13);
PAINT GREEN (12 -13);
DISPLAY INVISIBLE (12 -13);
WIRE 16 -1 (-7575 5500)(-6900 5500);
FORCEPROP 2 LAST SIG_NAME SPI_CPU1_CLK
J 0
(-7460 5510);
DISPLAY 0.489362 (-7460 5510);
WIRE 16 -1 (-6700 5500)(-5775 5500);
FORCEPROP 2 LAST SIG_NAME SPI_CPU1_R_CLK
J 0
(-6535 5510);
DISPLAY 0.489362 (-6535 5510);
FORCEPROP 2 LASTPROP $XRERR UNIQUE?
J 0
(-6775 5510);
DISPLAY 0.638298 (-6775 5510);
PAINT MONO (-6775 5510);
DISPLAY INVISIBLE (-6775 5510);
WIRE 16 -1 (-7575 4250)(-5775 4250);
FORCEPROP 2 LAST SIG_NAME PD_ESPI_CPU1_CLK2
J 0
(-7410 4260);
DISPLAY 0.489362 (-7410 4260);
WIRE 16 -1 (-3275 3950)(-2075 3950);
FORCEPROP 2 LAST SIG_NAME NC_CPU1_USB3_USB11_TXN
J 0
(-2985 3960);
DISPLAY 0.489362 (-2985 3960);
FORCEPROP 2 LASTPROP $XRERR UNIQUE?
J 0
(-2045 3950);
DISPLAY 0.638298 (-2045 3950);
PAINT MONO (-2045 3950);
DISPLAY INVISIBLE (-2045 3950);
WIRE 16 -1 (-3275 4000)(-2075 4000);
FORCEPROP 2 LAST SIG_NAME NC_CPU1_USB3_USB11_TXP
J 0
(-2985 4010);
DISPLAY 0.489362 (-2985 4010);
FORCEPROP 2 LASTPROP $XRERR UNIQUE?
J 0
(-2045 4000);
DISPLAY 0.638298 (-2045 4000);
PAINT MONO (-2045 4000);
DISPLAY INVISIBLE (-2045 4000);
WIRE 16 -1 (-3275 3700)(-2075 3700);
FORCEPROP 2 LAST SIG_NAME NC_CPU1_USB10_OC_N
J 0
(-2985 3710);
DISPLAY 0.489362 (-2985 3710);
FORCEPROP 2 LASTPROP $XRERR UNIQUE?
J 0
(-2045 3700);
DISPLAY 0.638298 (-2045 3700);
PAINT MONO (-2045 3700);
DISPLAY INVISIBLE (-2045 3700);
WIRE 16 -1 (-3275 3650)(-2075 3650);
FORCEPROP 2 LAST SIG_NAME NC_CPU1_USB11_OC_N
J 0
(-2985 3660);
DISPLAY 0.489362 (-2985 3660);
FORCEPROP 2 LASTPROP $XRERR UNIQUE?
J 0
(-2045 3650);
DISPLAY 0.638298 (-2045 3650);
PAINT MONO (-2045 3650);
DISPLAY INVISIBLE (-2045 3650);
WIRE 16 -1 (-3275 3800)(-2075 3800);
FORCEPROP 2 LAST SIG_NAME NC_CPU1_USB00_OC_N
J 0
(-2985 3810);
DISPLAY 0.489362 (-2985 3810);
FORCEPROP 2 LASTPROP $XRERR UNIQUE?
J 0
(-2045 3800);
DISPLAY 0.638298 (-2045 3800);
PAINT MONO (-2045 3800);
DISPLAY INVISIBLE (-2045 3800);
WIRE 16 -1 (-3275 3750)(-2075 3750);
FORCEPROP 2 LAST SIG_NAME NC_CPU1_USB01_OC_N
J 0
(-2985 3760);
DISPLAY 0.489362 (-2985 3760);
FORCEPROP 2 LASTPROP $XRERR UNIQUE?
J 0
(-2045 3750);
DISPLAY 0.638298 (-2045 3750);
PAINT MONO (-2045 3750);
DISPLAY INVISIBLE (-2045 3750);
WIRE 16 -1 (-3275 5700)(-2075 5700);
FORCEPROP 2 LAST SIG_NAME NC_CPU1_USB2_USB00_DN
J 0
(-2985 5710);
DISPLAY 0.489362 (-2985 5710);
FORCEPROP 2 LASTPROP $XRERR UNIQUE?
J 0
(-2045 5700);
DISPLAY 0.638298 (-2045 5700);
PAINT MONO (-2045 5700);
DISPLAY INVISIBLE (-2045 5700);
WIRE 16 -1 (-3275 5750)(-2075 5750);
FORCEPROP 2 LAST SIG_NAME NC_CPU1_USB2_USB00_DP
J 0
(-2985 5760);
DISPLAY 0.489362 (-2985 5760);
FORCEPROP 2 LASTPROP $XRERR UNIQUE?
J 0
(-2045 5750);
DISPLAY 0.638298 (-2045 5750);
PAINT MONO (-2045 5750);
DISPLAY INVISIBLE (-2045 5750);
WIRE 16 -1 (-3275 5050)(-2075 5050);
FORCEPROP 2 LAST SIG_NAME NC_CPU1_USB3_USB00_RXN
J 0
(-2985 5060);
DISPLAY 0.489362 (-2985 5060);
FORCEPROP 2 LASTPROP $XRERR UNIQUE?
J 0
(-2045 5050);
DISPLAY 0.638298 (-2045 5050);
PAINT MONO (-2045 5050);
DISPLAY INVISIBLE (-2045 5050);
WIRE 16 -1 (-3275 5100)(-2075 5100);
FORCEPROP 2 LAST SIG_NAME NC_CPU1_USB3_USB00_RXP
J 0
(-2985 5110);
DISPLAY 0.489362 (-2985 5110);
FORCEPROP 2 LASTPROP $XRERR UNIQUE?
J 0
(-2045 5100);
DISPLAY 0.638298 (-2045 5100);
PAINT MONO (-2045 5100);
DISPLAY INVISIBLE (-2045 5100);
WIRE 16 -1 (-3275 4400)(-2075 4400);
FORCEPROP 2 LAST SIG_NAME NC_CPU1_USB3_USB00_TXP
J 0
(-2985 4410);
DISPLAY 0.489362 (-2985 4410);
FORCEPROP 2 LASTPROP $XRERR UNIQUE?
J 0
(-2045 4400);
DISPLAY 0.638298 (-2045 4400);
PAINT MONO (-2045 4400);
DISPLAY INVISIBLE (-2045 4400);
WIRE 16 -1 (-3275 4450)(-2075 4450);
FORCEPROP 2 LAST SIG_NAME NC_CPU1_USB3_USB00_TXN
J 0
(-2985 4460);
DISPLAY 0.489362 (-2985 4460);
FORCEPROP 2 LASTPROP $XRERR UNIQUE?
J 0
(-2045 4450);
DISPLAY 0.638298 (-2045 4450);
PAINT MONO (-2045 4450);
DISPLAY INVISIBLE (-2045 4450);
WIRE 16 -1 (-3275 5550)(-2075 5550);
FORCEPROP 2 LAST SIG_NAME NC_CPU1_USB2_USB01_DN
J 0
(-2985 5560);
DISPLAY 0.489362 (-2985 5560);
FORCEPROP 2 LASTPROP $XRERR UNIQUE?
J 0
(-2045 5550);
DISPLAY 0.638298 (-2045 5550);
PAINT MONO (-2045 5550);
DISPLAY INVISIBLE (-2045 5550);
WIRE 16 -1 (-3275 5600)(-2075 5600);
FORCEPROP 2 LAST SIG_NAME NC_CPU1_USB2_USB01_DP
J 0
(-2985 5610);
DISPLAY 0.489362 (-2985 5610);
FORCEPROP 2 LASTPROP $XRERR UNIQUE?
J 0
(-2045 5600);
DISPLAY 0.638298 (-2045 5600);
PAINT MONO (-2045 5600);
DISPLAY INVISIBLE (-2045 5600);
WIRE 16 -1 (-3275 4900)(-2075 4900);
FORCEPROP 2 LAST SIG_NAME NC_CPU1_USB3_USB01_RXN
J 0
(-2985 4910);
DISPLAY 0.489362 (-2985 4910);
FORCEPROP 2 LASTPROP $XRERR UNIQUE?
J 0
(-2045 4900);
DISPLAY 0.638298 (-2045 4900);
PAINT MONO (-2045 4900);
DISPLAY INVISIBLE (-2045 4900);
WIRE 16 -1 (-3275 4950)(-2075 4950);
FORCEPROP 2 LAST SIG_NAME NC_CPU1_USB3_USB01_RXP
J 0
(-2985 4960);
DISPLAY 0.489362 (-2985 4960);
FORCEPROP 2 LASTPROP $XRERR UNIQUE?
J 0
(-2045 4950);
DISPLAY 0.638298 (-2045 4950);
PAINT MONO (-2045 4950);
DISPLAY INVISIBLE (-2045 4950);
WIRE 16 -1 (-3275 4250)(-2075 4250);
FORCEPROP 2 LAST SIG_NAME NC_CPU1_USB3_USB01_TXN
J 0
(-2985 4260);
DISPLAY 0.489362 (-2985 4260);
FORCEPROP 2 LASTPROP $XRERR UNIQUE?
J 0
(-2045 4250);
DISPLAY 0.638298 (-2045 4250);
PAINT MONO (-2045 4250);
DISPLAY INVISIBLE (-2045 4250);
WIRE 16 -1 (-3275 4300)(-2075 4300);
FORCEPROP 2 LAST SIG_NAME NC_CPU1_USB3_USB01_TXP
J 0
(-2985 4310);
DISPLAY 0.489362 (-2985 4310);
FORCEPROP 2 LASTPROP $XRERR UNIQUE?
J 0
(-2045 4300);
DISPLAY 0.638298 (-2045 4300);
PAINT MONO (-2045 4300);
DISPLAY INVISIBLE (-2045 4300);
WIRE 16 -1 (-3275 5400)(-2075 5400);
FORCEPROP 2 LAST SIG_NAME NC_CPU1_USB2_USB10_DN
J 0
(-2985 5410);
DISPLAY 0.489362 (-2985 5410);
FORCEPROP 2 LASTPROP $XRERR UNIQUE?
J 0
(-2045 5400);
DISPLAY 0.638298 (-2045 5400);
PAINT MONO (-2045 5400);
DISPLAY INVISIBLE (-2045 5400);
WIRE 16 -1 (-3275 5450)(-2075 5450);
FORCEPROP 2 LAST SIG_NAME NC_CPU1_USB2_USB10_DP
J 0
(-2985 5460);
DISPLAY 0.489362 (-2985 5460);
FORCEPROP 2 LASTPROP $XRERR UNIQUE?
J 0
(-2045 5450);
DISPLAY 0.638298 (-2045 5450);
PAINT MONO (-2045 5450);
DISPLAY INVISIBLE (-2045 5450);
WIRE 16 -1 (-3275 4750)(-2075 4750);
FORCEPROP 2 LAST SIG_NAME NC_CPU1_USB3_USB10_RXN
J 0
(-2985 4760);
DISPLAY 0.489362 (-2985 4760);
FORCEPROP 2 LASTPROP $XRERR UNIQUE?
J 0
(-2045 4750);
DISPLAY 0.638298 (-2045 4750);
PAINT MONO (-2045 4750);
DISPLAY INVISIBLE (-2045 4750);
WIRE 16 -1 (-3275 4800)(-2075 4800);
FORCEPROP 2 LAST SIG_NAME NC_CPU1_USB3_USB10_RXP
J 0
(-2985 4810);
DISPLAY 0.489362 (-2985 4810);
FORCEPROP 2 LASTPROP $XRERR UNIQUE?
J 0
(-2045 4800);
DISPLAY 0.638298 (-2045 4800);
PAINT MONO (-2045 4800);
DISPLAY INVISIBLE (-2045 4800);
WIRE 16 -1 (-3275 4100)(-2075 4100);
FORCEPROP 2 LAST SIG_NAME NC_CPU1_USB3_USB10_TXN
J 0
(-2985 4110);
DISPLAY 0.489362 (-2985 4110);
FORCEPROP 2 LASTPROP $XRERR UNIQUE?
J 0
(-2045 4100);
DISPLAY 0.638298 (-2045 4100);
PAINT MONO (-2045 4100);
DISPLAY INVISIBLE (-2045 4100);
WIRE 16 -1 (-3275 4150)(-2075 4150);
FORCEPROP 2 LAST SIG_NAME NC_CPU1_USB3_USB10_TXP
J 0
(-2985 4160);
DISPLAY 0.489362 (-2985 4160);
FORCEPROP 2 LASTPROP $XRERR UNIQUE?
J 0
(-2045 4150);
DISPLAY 0.638298 (-2045 4150);
PAINT MONO (-2045 4150);
DISPLAY INVISIBLE (-2045 4150);
WIRE 16 -1 (-3275 5250)(-2075 5250);
FORCEPROP 2 LAST SIG_NAME NC_CPU1_USB2_USB11_DN
J 0
(-2985 5260);
DISPLAY 0.489362 (-2985 5260);
FORCEPROP 2 LASTPROP $XRERR UNIQUE?
J 0
(-2045 5250);
DISPLAY 0.638298 (-2045 5250);
PAINT MONO (-2045 5250);
DISPLAY INVISIBLE (-2045 5250);
WIRE 16 -1 (-3275 5300)(-2075 5300);
FORCEPROP 2 LAST SIG_NAME NC_CPU1_USB2_USB11_DP
J 0
(-2985 5310);
DISPLAY 0.489362 (-2985 5310);
FORCEPROP 2 LASTPROP $XRERR UNIQUE?
J 0
(-2045 5300);
DISPLAY 0.638298 (-2045 5300);
PAINT MONO (-2045 5300);
DISPLAY INVISIBLE (-2045 5300);
WIRE 16 -1 (-3275 4600)(-2075 4600);
FORCEPROP 2 LAST SIG_NAME NC_CPU1_USB3_USB11_RXN
J 0
(-2985 4610);
DISPLAY 0.489362 (-2985 4610);
FORCEPROP 2 LASTPROP $XRERR UNIQUE?
J 0
(-2045 4600);
DISPLAY 0.638298 (-2045 4600);
PAINT MONO (-2045 4600);
DISPLAY INVISIBLE (-2045 4600);
WIRE 16 -1 (-3275 4650)(-2075 4650);
FORCEPROP 2 LAST SIG_NAME NC_CPU1_USB3_USB11_RXP
J 0
(-2985 4660);
DISPLAY 0.489362 (-2985 4660);
FORCEPROP 2 LASTPROP $XRERR UNIQUE?
J 0
(-2045 4650);
DISPLAY 0.638298 (-2045 4650);
PAINT MONO (-2045 4650);
DISPLAY INVISIBLE (-2045 4650);
QUIT
